#ISCELL
  pure_quanta quanta_title_block_c *
  *
#CELL
  pure_quanta cyusb330468ltxi *
  page154_i1
#CELL
  pure_quanta q_cap *
  page154_i10
#ISCELL
  pure_quanta_power gnd *
  page154_i11
#CELL
  pure_quanta q_cap *
  page154_i12
#CELL
  pure_quanta q_cap *
  page154_i13
#CELL
  pure_quanta q_cap *
  page154_i14
#CELL
  pure_quanta q_cap *
  page154_i15
#ISCELL
  pure_quanta_power gnd *
  page154_i16
#CELL
  pure_quanta q_cap *
  page154_i17
#ISCELL
  pure_quanta_power gnd *
  page154_i18
#CELL
  pure_quanta q_cap *
  page154_i19
#ISCELL
  pure_quanta_power universal_power *
  page154_i2
#CELL
  pure_quanta q_cap *
  page154_i20
#CELL
  pure_quanta q_cap *
  page154_i21
#CELL
  pure_quanta q_cap *
  page154_i22
#CELL
  pure_quanta q_cap *
  page154_i23
#ISCELL
  pure_quanta_power gnd *
  page154_i24
#ISCELL
  pure_quanta_power gnd *
  page154_i25
#CELL
  pure_quanta q_inductor *
  page154_i26
#CELL
  pure_quanta q_cap *
  page154_i27
#ISCELL
  pure_quanta_power gnd *
  page154_i28
#CELL
  pure_quanta q_cap *
  page154_i29
#CELL
  pure_quanta q_inductor *
  page154_i3
#ISCELL
  pure_quanta_power universal_power *
  page154_i30
#CELL
  pure_quanta q_cap *
  page154_i31
#CELL
  pure_quanta q_cap *
  page154_i32
#ISCELL
  pure_quanta_power gnd *
  page154_i33
#CELL
  pure_quanta q_cap *
  page154_i34
#CELL
  pure_quanta q_cap *
  page154_i35
#ISCELL
  pure_quanta_power gnd *
  page154_i36
#CELL
  pure_quanta q_cap *
  page154_i37
#CELL
  pure_quanta q_cap *
  page154_i38
#ISCELL
  pure_quanta_power gnd *
  page154_i39
#ISCELL
  pure_quanta_power universal_power *
  page154_i4
#CELL
  pure_quanta q_cap *
  page154_i40
#CELL
  pure_quanta q_cap *
  page154_i41
#ISCELL
  pure_quanta_power gnd *
  page154_i42
#CELL
  pure_quanta q_cap *
  page154_i43
#CELL
  pure_quanta q_cap *
  page154_i44
#ISCELL
  pure_quanta_power gnd *
  page154_i45
#CELL
  pure_quanta q_cap *
  page154_i46
#CELL
  pure_quanta q_cap *
  page154_i47
#ISCELL
  pure_quanta_power gnd *
  page154_i48
#CELL
  pure_quanta q_cap *
  page154_i49
#CELL
  pure_quanta q_cap *
  page154_i5
#CELL
  pure_quanta q_cap *
  page154_i50
#ISCELL
  pure_quanta_power gnd *
  page154_i51
#CELL
  pure_quanta q_cap *
  page154_i52
#CELL
  pure_quanta q_cap *
  page154_i53
#ISCELL
  pure_quanta_power gnd *
  page154_i54
#CELL
  pure_quanta q_cap *
  page154_i55
#CELL
  pure_quanta q_cap *
  page154_i56
#ISCELL
  pure_quanta_power gnd *
  page154_i57
#CELL
  pure_quanta q_cap *
  page154_i58
#CELL
  pure_quanta q_cap *
  page154_i59
#CELL
  pure_quanta q_cap *
  page154_i60
#ISCELL
  pure_quanta_power gnd *
  page154_i61
#ISCELL
  pure_quanta_power gnd *
  page154_i62
#CELL
  pure_quanta q_cap *
  page154_i63
#CELL
  pure_quanta q_cap *
  page154_i64
#CELL
  pure_quanta q_cap *
  page154_i65
#CELL
  pure_quanta q_cap *
  page154_i66
#ISCELL
  pure_quanta_power gnd *
  page154_i67
#CELL
  pure_quanta q_cap *
  page154_i68
#CELL
  pure_quanta q_cap *
  page154_i69
#CELL
  pure_quanta q_cap *
  page154_i7
#ISCELL
  pure_quanta_power gnd *
  page154_i70
#CELL
  pure_quanta q_cap *
  page154_i71
#ISCELL
  pure_quanta_power gnd *
  page154_i72
#CELL
  pure_quanta q_cap *
  page154_i73
#CELL
  pure_quanta q_cap *
  page154_i74
#CELL
  pure_quanta q_cap *
  page154_i75
#CELL
  pure_quanta q_cap *
  page154_i76
#ISCELL
  pure_quanta_power gnd *
  page154_i77
#CELL
  pure_quanta q_cap *
  page154_i78
#CELL
  pure_quanta q_cap *
  page154_i79
#ISCELL
  pure_quanta_power gnd *
  page154_i8
#ISCELL
  pure_quanta_power gnd *
  page154_i80
#CELL
  pure_quanta q_cap *
  page154_i81
#CELL
  pure_quanta q_cap *
  page154_i82
#CELL
  pure_quanta q_cap *
  page154_i83
#ISCELL
  pure_quanta_power gnd *
  page154_i84
#ISCELL
  pure_quanta_power universal_power *
  page154_i85
#ISCELL
  pure_quanta_power universal_power *
  page154_i86
#ISCELL
  pure_quanta_power universal_power *
  page154_i87
#ISCELL
  pure_quanta_power universal_power *
  page154_i88
#CELL
  pure_quanta q_cap *
  page154_i9
